# S9S_MB_2U (Grand Teton) — schematic netlist excerpt (pin names and nets, part order shuffled) for the footprints in the layout excerpt that follows; sources: Cadence DE-HDL packaged netlist, KiCad conversion of 03242023_DA0F0TMBIJ0_F0T_Motherboard_J_brd_V01_OCP.brd

PR276  Q_RES  1K 1% EMPTY  pkg 0402LF  page 292 : A = PVCCINFAON_CPU1_VIN_CSNIN ; B = GND
R1385  Q_RES  2K 1% EMPTY  pkg 0402LF  page 241 : A = SMB_SML0_3V3AUX_SDA ; B = P3V3_AUX
C336  Q_CAP  47UF 4V 20% X6S  pkg C0805  page 78 : A = PVCCIN_CPU1 ; B = GND

(kicad_pcb
	(version 20260206)
	(generator "pcbnew")
	(generator_version "10.0")
	(general
		(thickness 1.6)
		(legacy_teardrops no)
	)
	(paper "A4")
	(title_block
		(title "03242023_DA0F0TMBIJ0_F0T_Motherboard_J_brd_V01_OCP.brd")
		(comment 1 "Grand Teton / footprints 4485-4487 of 6105")
	)
	(layers
		(0 "F.Cu" signal "TOP")
		(4 "In1.Cu" signal "GND")
		(6 "In2.Cu" signal "IN1")
		(8 "In3.Cu" signal "GND1")
		(10 "In4.Cu" signal "IN2")
		(12 "In5.Cu" signal "GND2")
		(14 "In6.Cu" signal "IN3")
		(16 "In7.Cu" signal "GND3")
		(18 "In8.Cu" signal "VCC")
		(20 "In9.Cu" signal "VCC1")
		(22 "In10.Cu" signal "GND4")
		(24 "In11.Cu" signal "IN4")
		(26 "In12.Cu" signal "GND5")
		(28 "In13.Cu" signal "IN5")
		(30 "In14.Cu" signal "GND6")
		(32 "In15.Cu" signal "IN6")
		(34 "In16.Cu" signal "GND7")
		(2 "B.Cu" signal "BOTTOM")
		(9 "F.Adhes" user "F.Adhesive")
		(11 "B.Adhes" user "B.Adhesive")
		(13 "F.Paste" user "Package Geometry/Pastemask Top")
		(15 "B.Paste" user "Package Geometry/Pastemask Bottom")
		(5 "F.SilkS" user "Ref Des/Silkscreen Top")
		(7 "B.SilkS" user "Ref Des/Silkscreen Bottom")
		(1 "F.Mask" user "Board Geometry/Soldermask Top")
		(3 "B.Mask" user "Board Geometry/Soldermask Bottom")
		(17 "Dwgs.User" user "User.Drawings")
		(19 "Cmts.User" user "User.Comments")
		(21 "Eco1.User" user "User.Eco1")
		(23 "Eco2.User" user "User.Eco2")
		(25 "Edge.Cuts" user "Board Geometry/Outline")
		(27 "Margin" user)
		(31 "F.CrtYd" user "Package Geometry/Place Bound Top")
		(29 "B.CrtYd" user "Package Geometry/Place Bound Bottom")
		(35 "F.Fab" user "Ref Des/Assembly Top")
		(33 "B.Fab" user "Ref Des/Assembly Bottom")
	)
	(footprint ""
		(layer "B.Cu")
		(at 30.155896 -127.416052 180)
		(property "Reference" "PR276"
			(at 0 0 0)
			(layer "B.SilkS")
			(hide yes)
			(effects
				(font
					(size 1.27 1.27)
				)
				(justify mirror)
			)
		)
		(property "Value" ""
			(at 0 0 0)
			(layer "B.Fab")
			(effects
				(font
					(size 1.27 1.27)
				)
				(justify mirror)
			)
		)
		(duplicate_pad_numbers_are_jumpers no)
		(fp_line
			(start 0.7874 0.4064)
			(end 0.7874 -0.4064)
			(stroke
				(width 0.1524)
				(type default)
			)
			(layer "B.SilkS")
		)
		(fp_line
			(start 0.7874 -0.4064)
			(end -0.7874 -0.4064)
			(stroke
				(width 0.1524)
				(type default)
			)
			(layer "B.SilkS")
		)
		(fp_line
			(start -0.7874 0.4064)
			(end 0.7874 0.4064)
			(stroke
				(width 0.1524)
				(type default)
			)
			(layer "B.SilkS")
		)
		(fp_line
			(start -0.7874 -0.4064)
			(end -0.7874 0.4064)
			(stroke
				(width 0.1524)
				(type default)
			)
			(layer "B.SilkS")
		)
		(fp_line
			(start 0.67945 0.3048)
			(end 0.67945 -0.305054)
			(stroke
				(width 0.1)
				(type default)
			)
			(layer "B.Fab")
		)
		(fp_line
			(start 0.67945 -0.305054)
			(end 0.12065 -0.305054)
			(stroke
				(width 0.1)
				(type default)
			)
			(layer "B.Fab")
		)
		(fp_line
			(start 0.12065 0.3048)
			(end 0.67945 0.3048)
			(stroke
				(width 0.1)
				(type default)
			)
			(layer "B.Fab")
		)
		(fp_line
			(start 0.12065 0.2794)
			(end 0.12065 0.3048)
			(stroke
				(width 0.1)
				(type default)
			)
			(layer "B.Fab")
		)
		(fp_line
			(start 0.12065 -0.2794)
			(end -0.12065 -0.2794)
			(stroke
				(width 0.1)
				(type default)
			)
			(layer "B.Fab")
		)
		(fp_line
			(start 0.12065 -0.305054)
			(end 0.12065 -0.2794)
			(stroke
				(width 0.1)
				(type default)
			)
			(layer "B.Fab")
		)
		(fp_line
			(start -0.120396 0.3048)
			(end -0.120396 0.2794)
			(stroke
				(width 0.1)
				(type default)
			)
			(layer "B.Fab")
		)
		(fp_line
			(start -0.120396 0.2794)
			(end 0.12065 0.2794)
			(stroke
				(width 0.1)
				(type default)
			)
			(layer "B.Fab")
		)
		(fp_line
			(start -0.12065 -0.2794)
			(end -0.12065 -0.3048)
			(stroke
				(width 0.1)
				(type default)
			)
			(layer "B.Fab")
		)
		(fp_line
			(start -0.12065 -0.3048)
			(end -0.67945 -0.3048)
			(stroke
				(width 0.1)
				(type default)
			)
			(layer "B.Fab")
		)
		(fp_line
			(start -0.67945 0.3048)
			(end -0.120396 0.3048)
			(stroke
				(width 0.1)
				(type default)
			)
			(layer "B.Fab")
		)
		(fp_line
			(start -0.67945 -0.3048)
			(end -0.67945 0.3048)
			(stroke
				(width 0.1)
				(type default)
			)
			(layer "B.Fab")
		)
		(pad "1" smd circle
			(at 0.40005 0)
			(size 0 0)
			(layers "B.Cu" "B.Mask" "B.Paste")
			(net "PVCCINFAON_CPU1_VIN_CSNIN")
		)
		(pad "2" smd circle
			(at -0.40005 0)
			(size 0 0)
			(layers "B.Cu" "B.Mask" "B.Paste")
			(net "GND")
		)
	)
	(footprint ""
		(layer "B.Cu")
		(at 105.679494 -248.49836 -90)
		(property "Reference" "C336"
			(at 0 0 90)
			(layer "B.SilkS")
			(hide yes)
			(effects
				(font
					(size 1.27 1.27)
				)
				(justify mirror)
			)
		)
		(property "Value" ""
			(at 0 0 90)
			(layer "B.Fab")
			(effects
				(font
					(size 1.27 1.27)
				)
				(justify mirror)
			)
		)
		(duplicate_pad_numbers_are_jumpers no)
		(fp_line
			(start -1.524 0.762)
			(end 1.524 0.762)
			(stroke
				(width 0.1524)
				(type default)
			)
			(layer "B.SilkS")
		)
		(fp_line
			(start 1.524 0.762)
			(end 1.524 -0.762)
			(stroke
				(width 0.1524)
				(type default)
			)
			(layer "B.SilkS")
		)
		(fp_line
			(start -1.524 -0.762)
			(end -1.524 0.762)
			(stroke
				(width 0.1524)
				(type default)
			)
			(layer "B.SilkS")
		)
		(fp_line
			(start 1.524 -0.762)
			(end -1.524 -0.762)
			(stroke
				(width 0.1524)
				(type default)
			)
			(layer "B.SilkS")
		)
		(fp_line
			(start -1.1049 0.724916)
			(end -1.1049 -0.724916)
			(stroke
				(width 0.1)
				(type default)
			)
			(layer "B.Fab")
		)
		(fp_line
			(start 1.1049 0.724916)
			(end -1.1049 0.724916)
			(stroke
				(width 0.1)
				(type default)
			)
			(layer "B.Fab")
		)
		(fp_line
			(start -1.1049 -0.724916)
			(end 1.1049 -0.724916)
			(stroke
				(width 0.1)
				(type default)
			)
			(layer "B.Fab")
		)
		(fp_line
			(start 1.1049 -0.724916)
			(end 1.1049 0.724916)
			(stroke
				(width 0.1)
				(type default)
			)
			(layer "B.Fab")
		)
		(pad "1" smd rect
			(at 0.889 0 270)
			(size 1.016 1.27)
			(layers "B.Cu" "B.Mask" "B.Paste")
			(net "PVCCIN_CPU1")
		)
		(pad "2" smd rect
			(at -0.889 0 270)
			(size 1.016 1.27)
			(layers "B.Cu" "B.Mask" "B.Paste")
			(net "GND")
		)
	)
	(footprint ""
		(layer "B.Cu")
		(at 161.29 -15.712948 -90)
		(property "Reference" "R1385"
			(at 0 0 90)
			(layer "B.SilkS")
			(hide yes)
			(effects
				(font
					(size 1.27 1.27)
				)
				(justify mirror)
			)
		)
		(property "Value" ""
			(at 0 0 90)
			(layer "B.Fab")
			(effects
				(font
					(size 1.27 1.27)
				)
				(justify mirror)
			)
		)
		(duplicate_pad_numbers_are_jumpers no)
		(fp_line
			(start -0.7874 0.4064)
			(end 0.7874 0.4064)
			(stroke
				(width 0.1524)
				(type default)
			)
			(layer "B.SilkS")
		)
		(fp_line
			(start 0.7874 0.4064)
			(end 0.7874 -0.4064)
			(stroke
				(width 0.1524)
				(type default)
			)
			(layer "B.SilkS")
		)
		(fp_line
			(start -0.7874 -0.4064)
			(end -0.7874 0.4064)
			(stroke
				(width 0.1524)
				(type default)
			)
			(layer "B.SilkS")
		)
		(fp_line
			(start 0.7874 -0.4064)
			(end -0.7874 -0.4064)
			(stroke
				(width 0.1524)
				(type default)
			)
			(layer "B.SilkS")
		)
		(fp_line
			(start -0.67945 0.3048)
			(end -0.120396 0.3048)
			(stroke
				(width 0.1)
				(type default)
			)
			(layer "B.Fab")
		)
		(fp_line
			(start -0.120396 0.3048)
			(end -0.120396 0.2794)
			(stroke
				(width 0.1)
				(type default)
			)
			(layer "B.Fab")
		)
		(fp_line
			(start 0.12065 0.3048)
			(end 0.67945 0.3048)
			(stroke
				(width 0.1)
				(type default)
			)
			(layer "B.Fab")
		)
		(fp_line
			(start 0.67945 0.3048)
			(end 0.67945 -0.305054)
			(stroke
				(width 0.1)
				(type default)
			)
			(layer "B.Fab")
		)
		(fp_line
			(start -0.120396 0.2794)
			(end 0.12065 0.2794)
			(stroke
				(width 0.1)
				(type default)
			)
			(layer "B.Fab")
		)
		(fp_line
			(start 0.12065 0.2794)
			(end 0.12065 0.3048)
			(stroke
				(width 0.1)
				(type default)
			)
			(layer "B.Fab")
		)
		(fp_line
			(start -0.12065 -0.2794)
			(end -0.12065 -0.3048)
			(stroke
				(width 0.1)
				(type default)
			)
			(layer "B.Fab")
		)
		(fp_line
			(start 0.12065 -0.2794)
			(end -0.12065 -0.2794)
			(stroke
				(width 0.1)
				(type default)
			)
			(layer "B.Fab")
		)
		(fp_line
			(start -0.67945 -0.3048)
			(end -0.67945 0.3048)
			(stroke
				(width 0.1)
				(type default)
			)
			(layer "B.Fab")
		)
		(fp_line
			(start -0.12065 -0.3048)
			(end -0.67945 -0.3048)
			(stroke
				(width 0.1)
				(type default)
			)
			(layer "B.Fab")
		)
		(fp_line
			(start 0.12065 -0.305054)
			(end 0.12065 -0.2794)
			(stroke
				(width 0.1)
				(type default)
			)
			(layer "B.Fab")
		)
		(fp_line
			(start 0.67945 -0.305054)
			(end 0.12065 -0.305054)
			(stroke
				(width 0.1)
				(type default)
			)
			(layer "B.Fab")
		)
		(pad "1" smd circle
			(at 0.40005 0 90)
			(size 0 0)
			(layers "B.Cu" "B.Mask" "B.Paste")
			(net "SMB_SML0_3V3AUX_SDA")
		)
		(pad "2" smd circle
			(at -0.40005 0 90)
			(size 0 0)
			(layers "B.Cu" "B.Mask" "B.Paste")
			(net "P3V3_AUX")
		)
	)
)
